FILE_TYPE = MACRO_DRAWING;
SET COLOR_WIRE YELLOW;
SET COLOR_PROP ORANGE;
SET COLOR_DOT WHITE;
SET COLOR_ARC YELLOW;
SET COLOR_BODY GREEN;
SET COLOR_NOTE PURPLE;
SET PROP_DISPLAY VALUE;
SET PAGE_NUMBER P58;
SET PATH_NUMBER P71;
FORCEADD UNIVERSAL_GND..1
(-425 2275);
FORCEPROP 3 LASTPIN (-425 2325) SIG_NAME GND_P1\g
J 0
(-415 2335);
DISPLAY 0.659574 (-415 2335);
PAINT MONO (-415 2335);
DISPLAY INVISIBLE (-415 2335);
FORCEPROP 1 LAST HDL_POWER GND_P1
J 1
(-400 2200);
DISPLAY 0.702128 (-400 2200);
PAINT GREEN (-400 2200);
FORCEPROP 1 LAST PATH I18
J 0
(-350 2275);
DISPLAY 0.872340 (-350 2275);
PAINT AQUA (-350 2275);
DISPLAY INVISIBLE (-350 2275);
FORCEPROP 2 LAST CDS_LIB logical_power
J 0
(-425 2275);
DISPLAY INVISIBLE (-425 2275);
FORCEADD UNIVERSAL_GND..1
(-8075 3275);
FORCEPROP 3 LASTPIN (-8075 3325) SIG_NAME GND_P1\g
J 0
(-8065 3335);
DISPLAY 0.659574 (-8065 3335);
PAINT MONO (-8065 3335);
DISPLAY INVISIBLE (-8065 3335);
FORCEPROP 1 LAST HDL_POWER GND_P1
J 1
(-8050 3200);
DISPLAY 0.702128 (-8050 3200);
PAINT GREEN (-8050 3200);
FORCEPROP 1 LAST PATH I2
J 0
(-8000 3275);
DISPLAY 0.872340 (-8000 3275);
PAINT AQUA (-8000 3275);
DISPLAY INVISIBLE (-8000 3275);
FORCEPROP 2 LAST CDS_LIB logical_power
J 0
(-8075 3275);
DISPLAY INVISIBLE (-8075 3275);
FORCEADD UNIVERSAL_GND..1
(-3900 2275);
FORCEPROP 3 LASTPIN (-3900 2325) SIG_NAME GND_P1\g
J 0
(-3890 2335);
DISPLAY 0.659574 (-3890 2335);
PAINT MONO (-3890 2335);
DISPLAY INVISIBLE (-3890 2335);
FORCEPROP 1 LAST HDL_POWER GND_P1
J 1
(-3875 2200);
DISPLAY 0.702128 (-3875 2200);
PAINT GREEN (-3875 2200);
FORCEPROP 1 LAST PATH I25
J 0
(-3825 2275);
DISPLAY 0.872340 (-3825 2275);
PAINT AQUA (-3825 2275);
DISPLAY INVISIBLE (-3825 2275);
FORCEPROP 2 LAST CDS_LIB logical_power
J 0
(-3900 2275);
DISPLAY INVISIBLE (-3900 2275);
FORCEADD UNIVERSAL_GND..1
(-225 -800);
FORCEPROP 3 LASTPIN (-225 -750) SIG_NAME GND_P1\g
J 0
(-215 -740);
DISPLAY 0.659574 (-215 -740);
PAINT MONO (-215 -740);
DISPLAY INVISIBLE (-215 -740);
FORCEPROP 1 LAST HDL_POWER GND_P1
J 1
(-200 -875);
DISPLAY 0.702128 (-200 -875);
PAINT GREEN (-200 -875);
FORCEPROP 1 LAST PATH I35
J 0
(-150 -800);
DISPLAY 0.872340 (-150 -800);
PAINT AQUA (-150 -800);
DISPLAY INVISIBLE (-150 -800);
FORCEPROP 2 LAST CDS_LIB logical_power
J 0
(-225 -800);
DISPLAY INVISIBLE (-225 -800);
FORCEADD UNIVERSAL_GND..1
(-3700 -800);
FORCEPROP 3 LASTPIN (-3700 -750) SIG_NAME GND_P1\g
J 0
(-3690 -740);
DISPLAY 0.659574 (-3690 -740);
PAINT MONO (-3690 -740);
DISPLAY INVISIBLE (-3690 -740);
FORCEPROP 1 LAST HDL_POWER GND_P1
J 1
(-3675 -875);
DISPLAY 0.702128 (-3675 -875);
PAINT GREEN (-3675 -875);
FORCEPROP 1 LAST PATH I39
J 0
(-3625 -800);
DISPLAY 0.872340 (-3625 -800);
PAINT AQUA (-3625 -800);
DISPLAY INVISIBLE (-3625 -800);
FORCEPROP 2 LAST CDS_LIB logical_power
J 0
(-3700 -800);
DISPLAY INVISIBLE (-3700 -800);
FORCEADD UNIVERSAL_GND..1
(-4525 200);
FORCEPROP 3 LASTPIN (-4525 250) SIG_NAME GND_P1\g
J 0
(-4515 260);
DISPLAY 0.659574 (-4515 260);
PAINT MONO (-4515 260);
DISPLAY INVISIBLE (-4515 260);
FORCEPROP 1 LAST HDL_POWER GND_P1
J 1
(-4500 125);
DISPLAY 0.702128 (-4500 125);
PAINT GREEN (-4500 125);
FORCEPROP 1 LAST PATH I40
J 0
(-4450 200);
DISPLAY 0.872340 (-4450 200);
PAINT AQUA (-4450 200);
DISPLAY INVISIBLE (-4450 200);
FORCEPROP 2 LAST CDS_LIB logical_power
J 0
(-4525 200);
DISPLAY INVISIBLE (-4525 200);
FORCEADD UNIVERSAL_GND..1
(-8000 200);
FORCEPROP 3 LASTPIN (-8000 250) SIG_NAME GND_P1\g
J 0
(-7990 260);
DISPLAY 0.659574 (-7990 260);
PAINT MONO (-7990 260);
DISPLAY INVISIBLE (-7990 260);
FORCEPROP 1 LAST HDL_POWER GND_P1
J 1
(-7975 125);
DISPLAY 0.702128 (-7975 125);
PAINT GREEN (-7975 125);
FORCEPROP 1 LAST PATH I46
J 0
(-7925 200);
DISPLAY 0.872340 (-7925 200);
PAINT AQUA (-7925 200);
DISPLAY INVISIBLE (-7925 200);
FORCEPROP 2 LAST CDS_LIB logical_power
J 0
(-8000 200);
DISPLAY INVISIBLE (-8000 200);
FORCEADD UNIVERSAL_GND..1
(-7975 -725);
FORCEPROP 3 LASTPIN (-7975 -675) SIG_NAME GND_P1\g
J 0
(-7965 -665);
DISPLAY 0.659574 (-7965 -665);
PAINT MONO (-7965 -665);
DISPLAY INVISIBLE (-7965 -665);
FORCEPROP 1 LAST HDL_POWER GND_P1
J 1
(-7950 -800);
DISPLAY 0.702128 (-7950 -800);
PAINT GREEN (-7950 -800);
FORCEPROP 1 LAST PATH I47
J 0
(-7900 -725);
DISPLAY 0.872340 (-7900 -725);
PAINT AQUA (-7900 -725);
DISPLAY INVISIBLE (-7900 -725);
FORCEPROP 2 LAST CDS_LIB logical_power
J 0
(-7975 -725);
DISPLAY INVISIBLE (-7975 -725);
FORCEADD UNIVERSAL_GND..1
(-4500 -725);
FORCEPROP 3 LASTPIN (-4500 -675) SIG_NAME GND_P1\g
J 0
(-4490 -665);
DISPLAY 0.659574 (-4490 -665);
PAINT MONO (-4490 -665);
DISPLAY INVISIBLE (-4490 -665);
FORCEPROP 1 LAST HDL_POWER GND_P1
J 1
(-4475 -800);
DISPLAY 0.702128 (-4475 -800);
PAINT GREEN (-4475 -800);
FORCEPROP 1 LAST PATH I48
J 0
(-4425 -725);
DISPLAY 0.872340 (-4425 -725);
PAINT AQUA (-4425 -725);
DISPLAY INVISIBLE (-4425 -725);
FORCEPROP 2 LAST CDS_LIB logical_power
J 0
(-4500 -725);
DISPLAY INVISIBLE (-4500 -725);
FORCEADD UNIVERSAL_GND..1
(-3700 150);
FORCEPROP 3 LASTPIN (-3700 200) SIG_NAME GND_P1\g
J 0
(-3690 210);
DISPLAY 0.659574 (-3690 210);
PAINT MONO (-3690 210);
DISPLAY INVISIBLE (-3690 210);
FORCEPROP 1 LAST HDL_POWER GND_P1
J 1
(-3675 75);
DISPLAY 0.702128 (-3675 75);
PAINT GREEN (-3675 75);
FORCEPROP 1 LAST PATH I49
J 0
(-3625 150);
DISPLAY 0.872340 (-3625 150);
PAINT AQUA (-3625 150);
DISPLAY INVISIBLE (-3625 150);
FORCEPROP 2 LAST CDS_LIB logical_power
J 0
(-3700 150);
DISPLAY INVISIBLE (-3700 150);
FORCEADD UNIVERSAL_GND..1
(-4600 3275);
FORCEPROP 3 LASTPIN (-4600 3325) SIG_NAME GND_P1\g
J 0
(-4590 3335);
DISPLAY 0.659574 (-4590 3335);
PAINT MONO (-4590 3335);
DISPLAY INVISIBLE (-4590 3335);
FORCEPROP 1 LAST HDL_POWER GND_P1
J 1
(-4575 3200);
DISPLAY 0.702128 (-4575 3200);
PAINT GREEN (-4575 3200);
FORCEPROP 1 LAST PATH I5
J 0
(-4525 3275);
DISPLAY 0.872340 (-4525 3275);
PAINT AQUA (-4525 3275);
DISPLAY INVISIBLE (-4525 3275);
FORCEPROP 2 LAST CDS_LIB logical_power
J 0
(-4600 3275);
DISPLAY INVISIBLE (-4600 3275);
FORCEADD UNIVERSAL_GND..1
(-225 150);
FORCEPROP 3 LASTPIN (-225 200) SIG_NAME GND_P1\g
J 0
(-215 210);
DISPLAY 0.659574 (-215 210);
PAINT MONO (-215 210);
DISPLAY INVISIBLE (-215 210);
FORCEPROP 1 LAST HDL_POWER GND_P1
J 1
(-200 75);
DISPLAY 0.702128 (-200 75);
PAINT GREEN (-200 75);
FORCEPROP 1 LAST PATH I50
J 0
(-150 150);
DISPLAY 0.872340 (-150 150);
PAINT AQUA (-150 150);
DISPLAY INVISIBLE (-150 150);
FORCEPROP 2 LAST CDS_LIB logical_power
J 0
(-225 150);
DISPLAY INVISIBLE (-225 150);
FORCEADD UNIVERSAL_GND..1
(-3900 3225);
FORCEPROP 3 LASTPIN (-3900 3275) SIG_NAME GND_P1\g
J 0
(-3890 3285);
DISPLAY 0.659574 (-3890 3285);
PAINT MONO (-3890 3285);
DISPLAY INVISIBLE (-3890 3285);
FORCEPROP 1 LAST HDL_POWER GND_P1
J 1
(-3875 3150);
DISPLAY 0.702128 (-3875 3150);
PAINT GREEN (-3875 3150);
FORCEPROP 1 LAST PATH I51
J 0
(-3825 3225);
DISPLAY 0.872340 (-3825 3225);
PAINT AQUA (-3825 3225);
DISPLAY INVISIBLE (-3825 3225);
FORCEPROP 2 LAST CDS_LIB logical_power
J 0
(-3900 3225);
DISPLAY INVISIBLE (-3900 3225);
FORCEADD UNIVERSAL_GND..1
(-425 3225);
FORCEPROP 3 LASTPIN (-425 3275) SIG_NAME GND_P1\g
J 0
(-415 3285);
DISPLAY 0.659574 (-415 3285);
PAINT MONO (-415 3285);
DISPLAY INVISIBLE (-415 3285);
FORCEPROP 1 LAST HDL_POWER GND_P1
J 1
(-400 3150);
DISPLAY 0.702128 (-400 3150);
PAINT GREEN (-400 3150);
FORCEPROP 1 LAST PATH I52
J 0
(-350 3225);
DISPLAY 0.872340 (-350 3225);
PAINT AQUA (-350 3225);
DISPLAY INVISIBLE (-350 3225);
FORCEPROP 2 LAST CDS_LIB logical_power
J 0
(-425 3225);
DISPLAY INVISIBLE (-425 3225);
FORCEADD UNIVERSAL_GND..1
(-4600 2400);
FORCEPROP 3 LASTPIN (-4600 2450) SIG_NAME GND_P1\g
J 0
(-4590 2460);
DISPLAY 0.659574 (-4590 2460);
PAINT MONO (-4590 2460);
DISPLAY INVISIBLE (-4590 2460);
FORCEPROP 1 LAST HDL_POWER GND_P1
J 1
(-4575 2325);
DISPLAY 0.702128 (-4575 2325);
PAINT GREEN (-4575 2325);
FORCEPROP 1 LAST PATH I53
J 0
(-4525 2400);
DISPLAY 0.872340 (-4525 2400);
PAINT AQUA (-4525 2400);
DISPLAY INVISIBLE (-4525 2400);
FORCEPROP 2 LAST CDS_LIB logical_power
J 0
(-4600 2400);
DISPLAY INVISIBLE (-4600 2400);
FORCEADD UNIVERSAL_GND..1
(-8075 2400);
FORCEPROP 3 LASTPIN (-8075 2450) SIG_NAME GND_P1\g
J 0
(-8065 2460);
DISPLAY 0.659574 (-8065 2460);
PAINT MONO (-8065 2460);
DISPLAY INVISIBLE (-8065 2460);
FORCEPROP 1 LAST HDL_POWER GND_P1
J 1
(-8050 2325);
DISPLAY 0.702128 (-8050 2325);
PAINT GREEN (-8050 2325);
FORCEPROP 1 LAST PATH I54
J 0
(-8000 2400);
DISPLAY 0.872340 (-8000 2400);
PAINT AQUA (-8000 2400);
DISPLAY INVISIBLE (-8000 2400);
FORCEPROP 2 LAST CDS_LIB logical_power
J 0
(-8075 2400);
DISPLAY INVISIBLE (-8075 2400);
FORCEADD PICOPROBE_BXA..1
(-7675 3625);
FORCEPROP 1 LAST MATERIAL EMPTY
J 0
(-7829 3730);
DISPLAY 0.723404 (-7829 3730);
PAINT GREEN (-7829 3730);
FORCEPROP 1 LAST PART_NUMBER TP33
J 0
(-7825 3775);
DISPLAY 0.723404 (-7825 3775);
PAINT GREEN (-7825 3775);
FORCEPROP 2 LAST PART_TYPE SMLF
J 0
(-7825 3925);
DISPLAY 0.680851 (-7825 3925);
FORCEPROP 2 LAST VALUE DELTA-L 4.0
J 0
(-7825 3875);
DISPLAY 0.680851 (-7825 3875);
FORCEPROP 1 LAST CDS_LMAN_SYM_OUTLINE -150,100,150,-100
J 0
(-7675 3625);
DISPLAY 0.468085 (-7675 3625);
PAINT GREEN (-7675 3625);
DISPLAY INVISIBLE (-7675 3625);
FORCEPROP 2 LAST CDS_LIB pure_quanta
J 0
(-7675 3625);
DISPLAY INVISIBLE (-7675 3625);
FORCEPROP 1 LAST PATH I55
J 0
(-7675 3625);
DISPLAY 0.723404 (-7675 3625);
PAINT GREEN (-7675 3625);
DISPLAY INVISIBLE (-7675 3625);
FORCEPROP 1 LAST NEEDS_NO_SIZE TRUE
J 0
(-7675 3625);
DISPLAY 0.723404 (-7675 3625);
PAINT GREEN (-7675 3625);
DISPLAY INVISIBLE (-7675 3625);
FORCEPROP 1 LAST LOCATION J9
J 0
(-7825 3825);
DISPLAY 0.723404 (-7825 3825);
PAINT GREEN (-7825 3825);
FORCEPROP 0 LASTPIN (-7375 3625) $PN 1
J 0
(-7365 3635);
DISPLAY 0.680851 (-7365 3635);
PAINT MONO (-7365 3635);
FORCEPROP 0 LASTPIN (-7375 3675) $PN 2
J 0
(-7365 3685);
DISPLAY 0.680851 (-7365 3685);
PAINT MONO (-7365 3685);
FORCEPROP 0 LASTPIN (-7975 3675) $PN 3
J 2
(-7985 3685);
DISPLAY 0.680851 (-7985 3685);
PAINT MONO (-7985 3685);
FORCEPROP 0 LAST $SEC 1
J 0
(-7825 3975);
DISPLAY 0.680851 (-7825 3975);
PAINT MONO (-7825 3975);
DISPLAY INVISIBLE (-7825 3975);
FORCEPROP 0 LAST CDS_SEC 1
J 0
(-7825 3975);
DISPLAY 0.680851 (-7825 3975);
DISPLAY INVISIBLE (-7825 3975);
FORCEADD PICOPROBE_BXA..1
(-7675 2750);
FORCEPROP 1 LAST PART_NUMBER TP33
J 0
(-7825 2900);
DISPLAY 0.723404 (-7825 2900);
PAINT GREEN (-7825 2900);
FORCEPROP 1 LAST MATERIAL EMPTY
J 0
(-7829 2855);
DISPLAY 0.723404 (-7829 2855);
PAINT GREEN (-7829 2855);
FORCEPROP 2 LAST VALUE DELTA-L 4.0
J 0
(-7825 3000);
DISPLAY 0.680851 (-7825 3000);
FORCEPROP 2 LAST PART_TYPE SMLF
J 0
(-7825 3050);
DISPLAY 0.680851 (-7825 3050);
FORCEPROP 2 LAST CDS_LIB pure_quanta
J 0
(-7675 2750);
DISPLAY INVISIBLE (-7675 2750);
FORCEPROP 1 LAST PATH I57
J 0
(-7675 2750);
DISPLAY 0.723404 (-7675 2750);
PAINT GREEN (-7675 2750);
DISPLAY INVISIBLE (-7675 2750);
FORCEPROP 1 LAST CDS_LMAN_SYM_OUTLINE -150,100,150,-100
J 0
(-7675 2750);
DISPLAY 0.468085 (-7675 2750);
PAINT GREEN (-7675 2750);
DISPLAY INVISIBLE (-7675 2750);
FORCEPROP 1 LAST NEEDS_NO_SIZE TRUE
J 0
(-7675 2750);
DISPLAY 0.723404 (-7675 2750);
PAINT GREEN (-7675 2750);
DISPLAY INVISIBLE (-7675 2750);
FORCEPROP 1 LAST LOCATION J11
J 0
(-7825 2950);
DISPLAY 0.723404 (-7825 2950);
PAINT GREEN (-7825 2950);
FORCEPROP 0 LASTPIN (-7375 2750) $PN 1
J 0
(-7365 2760);
DISPLAY 0.680851 (-7365 2760);
PAINT MONO (-7365 2760);
FORCEPROP 0 LASTPIN (-7375 2800) $PN 2
J 0
(-7365 2810);
DISPLAY 0.680851 (-7365 2810);
PAINT MONO (-7365 2810);
FORCEPROP 0 LASTPIN (-7975 2800) $PN 3
J 2
(-7985 2810);
DISPLAY 0.680851 (-7985 2810);
PAINT MONO (-7985 2810);
FORCEPROP 0 LAST $SEC 1
J 0
(-7825 3100);
DISPLAY 0.680851 (-7825 3100);
PAINT MONO (-7825 3100);
DISPLAY INVISIBLE (-7825 3100);
FORCEPROP 0 LAST CDS_SEC 1
J 0
(-7825 3100);
DISPLAY 0.680851 (-7825 3100);
DISPLAY INVISIBLE (-7825 3100);
FORCEADD PICOPROBE_BXA..1
(-3500 3575);
FORCEPROP 2 LAST VALUE DELTA-L 4.0
J 0
(-3650 3825);
DISPLAY 0.680851 (-3650 3825);
FORCEPROP 2 LAST PART_TYPE SMLF
J 0
(-3650 3875);
DISPLAY 0.680851 (-3650 3875);
FORCEPROP 1 LAST PART_NUMBER TP33
J 0
(-3650 3725);
DISPLAY 0.723404 (-3650 3725);
PAINT GREEN (-3650 3725);
FORCEPROP 1 LAST MATERIAL EMPTY
J 0
(-3654 3680);
DISPLAY 0.723404 (-3654 3680);
PAINT GREEN (-3654 3680);
FORCEPROP 1 LAST NEEDS_NO_SIZE TRUE
J 0
(-3500 3575);
DISPLAY 0.723404 (-3500 3575);
PAINT GREEN (-3500 3575);
DISPLAY INVISIBLE (-3500 3575);
FORCEPROP 1 LAST CDS_LMAN_SYM_OUTLINE -150,100,150,-100
J 0
(-3500 3575);
DISPLAY 0.468085 (-3500 3575);
PAINT GREEN (-3500 3575);
DISPLAY INVISIBLE (-3500 3575);
FORCEPROP 1 LAST PATH I58
J 0
(-3500 3575);
DISPLAY 0.723404 (-3500 3575);
PAINT GREEN (-3500 3575);
DISPLAY INVISIBLE (-3500 3575);
FORCEPROP 2 LAST CDS_LIB pure_quanta
J 0
(-3500 3575);
DISPLAY INVISIBLE (-3500 3575);
FORCEPROP 1 LAST LOCATION J16
J 0
(-3650 3775);
DISPLAY 0.723404 (-3650 3775);
PAINT GREEN (-3650 3775);
FORCEPROP 0 LASTPIN (-3200 3575) $PN 1
J 0
(-3190 3585);
DISPLAY 0.680851 (-3190 3585);
PAINT MONO (-3190 3585);
FORCEPROP 0 LASTPIN (-3200 3625) $PN 2
J 0
(-3190 3635);
DISPLAY 0.680851 (-3190 3635);
PAINT MONO (-3190 3635);
FORCEPROP 0 LASTPIN (-3800 3625) $PN 3
J 2
(-3810 3635);
DISPLAY 0.680851 (-3810 3635);
PAINT MONO (-3810 3635);
FORCEPROP 0 LAST $SEC 1
J 0
(-3650 3925);
DISPLAY 0.680851 (-3650 3925);
PAINT MONO (-3650 3925);
DISPLAY INVISIBLE (-3650 3925);
FORCEPROP 0 LAST CDS_SEC 1
J 0
(-3650 3925);
DISPLAY 0.680851 (-3650 3925);
DISPLAY INVISIBLE (-3650 3925);
FORCEADD PICOPROBE_BXA..1
(-3500 2650);
FORCEPROP 2 LAST VALUE DELTA-L 4.0
J 0
(-3650 2900);
DISPLAY 0.680851 (-3650 2900);
FORCEPROP 2 LAST PART_TYPE SMLF
J 0
(-3650 2950);
DISPLAY 0.680851 (-3650 2950);
FORCEPROP 1 LAST PART_NUMBER TP33
J 0
(-3650 2800);
DISPLAY 0.723404 (-3650 2800);
PAINT GREEN (-3650 2800);
FORCEPROP 1 LAST MATERIAL EMPTY
J 0
(-3654 2755);
DISPLAY 0.723404 (-3654 2755);
PAINT GREEN (-3654 2755);
FORCEPROP 1 LAST NEEDS_NO_SIZE TRUE
J 0
(-3500 2650);
DISPLAY 0.723404 (-3500 2650);
PAINT GREEN (-3500 2650);
DISPLAY INVISIBLE (-3500 2650);
FORCEPROP 1 LAST CDS_LMAN_SYM_OUTLINE -150,100,150,-100
J 0
(-3500 2650);
DISPLAY 0.468085 (-3500 2650);
PAINT GREEN (-3500 2650);
DISPLAY INVISIBLE (-3500 2650);
FORCEPROP 1 LAST PATH I59
J 0
(-3500 2650);
DISPLAY 0.723404 (-3500 2650);
PAINT GREEN (-3500 2650);
DISPLAY INVISIBLE (-3500 2650);
FORCEPROP 2 LAST CDS_LIB pure_quanta
J 0
(-3500 2650);
DISPLAY INVISIBLE (-3500 2650);
FORCEPROP 1 LAST LOCATION J17
J 0
(-3650 2850);
DISPLAY 0.723404 (-3650 2850);
PAINT GREEN (-3650 2850);
FORCEPROP 0 LASTPIN (-3200 2650) $PN 1
J 0
(-3190 2660);
DISPLAY 0.680851 (-3190 2660);
PAINT MONO (-3190 2660);
FORCEPROP 0 LASTPIN (-3200 2700) $PN 2
J 0
(-3190 2710);
DISPLAY 0.680851 (-3190 2710);
PAINT MONO (-3190 2710);
FORCEPROP 0 LASTPIN (-3800 2700) $PN 3
J 2
(-3810 2710);
DISPLAY 0.680851 (-3810 2710);
PAINT MONO (-3810 2710);
FORCEPROP 0 LAST $SEC 1
J 0
(-3650 3000);
DISPLAY 0.680851 (-3650 3000);
PAINT MONO (-3650 3000);
DISPLAY INVISIBLE (-3650 3000);
FORCEPROP 0 LAST CDS_SEC 1
J 0
(-3650 3000);
DISPLAY 0.680851 (-3650 3000);
DISPLAY INVISIBLE (-3650 3000);
FORCEADD PICOPROBE_BXA..1
(-7600 550);
FORCEPROP 2 LAST VALUE DELTA-L 4.0
J 0
(-7750 800);
DISPLAY 0.680851 (-7750 800);
FORCEPROP 2 LAST PART_TYPE SMLF
J 0
(-7750 850);
DISPLAY 0.680851 (-7750 850);
FORCEPROP 1 LAST PART_NUMBER TP33
J 0
(-7750 700);
DISPLAY 0.723404 (-7750 700);
PAINT GREEN (-7750 700);
FORCEPROP 1 LAST MATERIAL EMPTY
J 0
(-7754 655);
DISPLAY 0.723404 (-7754 655);
PAINT GREEN (-7754 655);
FORCEPROP 1 LAST NEEDS_NO_SIZE TRUE
J 0
(-7600 550);
DISPLAY 0.723404 (-7600 550);
PAINT GREEN (-7600 550);
DISPLAY INVISIBLE (-7600 550);
FORCEPROP 1 LAST CDS_LMAN_SYM_OUTLINE -150,100,150,-100
J 0
(-7600 550);
DISPLAY 0.468085 (-7600 550);
PAINT GREEN (-7600 550);
DISPLAY INVISIBLE (-7600 550);
FORCEPROP 1 LAST PATH I60
J 0
(-7600 550);
DISPLAY 0.723404 (-7600 550);
PAINT GREEN (-7600 550);
DISPLAY INVISIBLE (-7600 550);
FORCEPROP 2 LAST CDS_LIB pure_quanta
J 0
(-7600 550);
DISPLAY INVISIBLE (-7600 550);
FORCEPROP 1 LAST LOCATION J25
J 0
(-7750 750);
DISPLAY 0.723404 (-7750 750);
PAINT GREEN (-7750 750);
FORCEPROP 0 LASTPIN (-7300 550) $PN 1
J 0
(-7290 560);
DISPLAY 0.680851 (-7290 560);
PAINT MONO (-7290 560);
FORCEPROP 0 LASTPIN (-7300 600) $PN 2
J 0
(-7290 610);
DISPLAY 0.680851 (-7290 610);
PAINT MONO (-7290 610);
FORCEPROP 0 LASTPIN (-7900 600) $PN 3
J 2
(-7910 610);
DISPLAY 0.680851 (-7910 610);
PAINT MONO (-7910 610);
FORCEPROP 0 LAST $SEC 1
J 0
(-7750 900);
DISPLAY 0.680851 (-7750 900);
PAINT MONO (-7750 900);
DISPLAY INVISIBLE (-7750 900);
FORCEPROP 0 LAST CDS_SEC 1
J 0
(-7750 900);
DISPLAY 0.680851 (-7750 900);
DISPLAY INVISIBLE (-7750 900);
FORCEADD PICOPROBE_BXA..1
(-7575 -375);
FORCEPROP 1 LAST PART_NUMBER TP33
J 0
(-7725 -225);
DISPLAY 0.723404 (-7725 -225);
PAINT GREEN (-7725 -225);
FORCEPROP 1 LAST MATERIAL EMPTY
J 0
(-7729 -270);
DISPLAY 0.723404 (-7729 -270);
PAINT GREEN (-7729 -270);
FORCEPROP 2 LAST PART_TYPE SMLF
J 0
(-7725 -75);
DISPLAY 0.680851 (-7725 -75);
FORCEPROP 2 LAST VALUE DELTA-L 4.0
J 0
(-7725 -125);
DISPLAY 0.680851 (-7725 -125);
FORCEPROP 1 LAST NEEDS_NO_SIZE TRUE
J 0
(-7575 -375);
DISPLAY 0.723404 (-7575 -375);
PAINT GREEN (-7575 -375);
DISPLAY INVISIBLE (-7575 -375);
FORCEPROP 1 LAST CDS_LMAN_SYM_OUTLINE -150,100,150,-100
J 0
(-7575 -375);
DISPLAY 0.468085 (-7575 -375);
PAINT GREEN (-7575 -375);
DISPLAY INVISIBLE (-7575 -375);
FORCEPROP 1 LAST PATH I61
J 0
(-7575 -375);
DISPLAY 0.723404 (-7575 -375);
PAINT GREEN (-7575 -375);
DISPLAY INVISIBLE (-7575 -375);
FORCEPROP 2 LAST CDS_LIB pure_quanta
J 0
(-7575 -375);
DISPLAY INVISIBLE (-7575 -375);
FORCEPROP 1 LAST LOCATION J28
J 0
(-7725 -175);
DISPLAY 0.723404 (-7725 -175);
PAINT GREEN (-7725 -175);
FORCEPROP 0 LASTPIN (-7275 -375) $PN 1
J 0
(-7265 -365);
DISPLAY 0.680851 (-7265 -365);
PAINT MONO (-7265 -365);
FORCEPROP 0 LASTPIN (-7275 -325) $PN 2
J 0
(-7265 -315);
DISPLAY 0.680851 (-7265 -315);
PAINT MONO (-7265 -315);
FORCEPROP 0 LASTPIN (-7875 -325) $PN 3
J 2
(-7885 -315);
DISPLAY 0.680851 (-7885 -315);
PAINT MONO (-7885 -315);
FORCEPROP 0 LAST $SEC 1
J 0
(-7725 -25);
DISPLAY 0.680851 (-7725 -25);
PAINT MONO (-7725 -25);
DISPLAY INVISIBLE (-7725 -25);
FORCEPROP 0 LAST CDS_SEC 1
J 0
(-7725 -25);
DISPLAY 0.680851 (-7725 -25);
DISPLAY INVISIBLE (-7725 -25);
FORCEADD PICOPROBE_BXA..1
(-3300 500);
FORCEPROP 1 LAST PART_NUMBER TP33
J 0
(-3450 650);
DISPLAY 0.723404 (-3450 650);
PAINT GREEN (-3450 650);
FORCEPROP 2 LAST PART_TYPE SMLF
J 0
(-3450 800);
DISPLAY 0.680851 (-3450 800);
FORCEPROP 2 LAST VALUE DELTA-L 4.0
J 0
(-3450 750);
DISPLAY 0.680851 (-3450 750);
FORCEPROP 1 LAST MATERIAL EMPTY
J 0
(-3454 605);
DISPLAY 0.723404 (-3454 605);
PAINT GREEN (-3454 605);
FORCEPROP 1 LAST NEEDS_NO_SIZE TRUE
J 0
(-3300 500);
DISPLAY 0.723404 (-3300 500);
PAINT GREEN (-3300 500);
DISPLAY INVISIBLE (-3300 500);
FORCEPROP 1 LAST CDS_LMAN_SYM_OUTLINE -150,100,150,-100
J 0
(-3300 500);
DISPLAY 0.468085 (-3300 500);
PAINT GREEN (-3300 500);
DISPLAY INVISIBLE (-3300 500);
FORCEPROP 1 LAST PATH I62
J 0
(-3300 500);
DISPLAY 0.723404 (-3300 500);
PAINT GREEN (-3300 500);
DISPLAY INVISIBLE (-3300 500);
FORCEPROP 2 LAST CDS_LIB pure_quanta
J 0
(-3300 500);
DISPLAY INVISIBLE (-3300 500);
FORCEPROP 1 LAST LOCATION J26
J 0
(-3450 700);
DISPLAY 0.723404 (-3450 700);
PAINT GREEN (-3450 700);
FORCEPROP 0 LASTPIN (-3000 500) $PN 1
J 0
(-2990 510);
DISPLAY 0.680851 (-2990 510);
PAINT MONO (-2990 510);
FORCEPROP 0 LASTPIN (-3000 550) $PN 2
J 0
(-2990 560);
DISPLAY 0.680851 (-2990 560);
PAINT MONO (-2990 560);
FORCEPROP 0 LASTPIN (-3600 550) $PN 3
J 2
(-3610 560);
DISPLAY 0.680851 (-3610 560);
PAINT MONO (-3610 560);
FORCEPROP 0 LAST $SEC 1
J 0
(-3450 850);
DISPLAY 0.680851 (-3450 850);
PAINT MONO (-3450 850);
DISPLAY INVISIBLE (-3450 850);
FORCEPROP 0 LAST CDS_SEC 1
J 0
(-3450 850);
DISPLAY 0.680851 (-3450 850);
DISPLAY INVISIBLE (-3450 850);
FORCEADD PICOPROBE_BXA..1
(-3300 -425);
FORCEPROP 2 LAST PART_TYPE SMLF
J 0
(-3450 -125);
DISPLAY 0.680851 (-3450 -125);
FORCEPROP 1 LAST PART_NUMBER TP33
J 0
(-3450 -275);
DISPLAY 0.723404 (-3450 -275);
PAINT GREEN (-3450 -275);
FORCEPROP 1 LAST MATERIAL EMPTY
J 0
(-3454 -320);
DISPLAY 0.723404 (-3454 -320);
PAINT GREEN (-3454 -320);
FORCEPROP 2 LAST VALUE DELTA-L 4.0
J 0
(-3450 -175);
DISPLAY 0.680851 (-3450 -175);
FORCEPROP 1 LAST NEEDS_NO_SIZE TRUE
J 0
(-3300 -425);
DISPLAY 0.723404 (-3300 -425);
PAINT GREEN (-3300 -425);
DISPLAY INVISIBLE (-3300 -425);
FORCEPROP 1 LAST CDS_LMAN_SYM_OUTLINE -150,100,150,-100
J 0
(-3300 -425);
DISPLAY 0.468085 (-3300 -425);
PAINT GREEN (-3300 -425);
DISPLAY INVISIBLE (-3300 -425);
FORCEPROP 1 LAST PATH I63
J 0
(-3300 -425);
DISPLAY 0.723404 (-3300 -425);
PAINT GREEN (-3300 -425);
DISPLAY INVISIBLE (-3300 -425);
FORCEPROP 2 LAST CDS_LIB pure_quanta
J 0
(-3300 -425);
DISPLAY INVISIBLE (-3300 -425);
FORCEPROP 1 LAST LOCATION J27
J 0
(-3450 -225);
DISPLAY 0.723404 (-3450 -225);
PAINT GREEN (-3450 -225);
FORCEPROP 0 LASTPIN (-3000 -425) $PN 1
J 0
(-2990 -415);
DISPLAY 0.680851 (-2990 -415);
PAINT MONO (-2990 -415);
FORCEPROP 0 LASTPIN (-3000 -375) $PN 2
J 0
(-2990 -365);
DISPLAY 0.680851 (-2990 -365);
PAINT MONO (-2990 -365);
FORCEPROP 0 LASTPIN (-3600 -375) $PN 3
J 2
(-3610 -365);
DISPLAY 0.680851 (-3610 -365);
PAINT MONO (-3610 -365);
FORCEPROP 0 LAST $SEC 1
J 0
(-3450 -75);
DISPLAY 0.680851 (-3450 -75);
PAINT MONO (-3450 -75);
DISPLAY INVISIBLE (-3450 -75);
FORCEPROP 0 LAST CDS_SEC 1
J 0
(-3450 -75);
DISPLAY 0.680851 (-3450 -75);
DISPLAY INVISIBLE (-3450 -75);
FORCEADD PICOPROBE_BXA..1
R 4
(-5000 3675);
FORCEPROP 1 LAST MATERIAL EMPTY
R 2
J 0
(-4846 3570);
DISPLAY 0.723404 (-4846 3570);
PAINT GREEN (-4846 3570);
FORCEPROP 1 LAST PART_NUMBER TP33
R 2
J 0
(-4850 3525);
DISPLAY 0.723404 (-4850 3525);
PAINT GREEN (-4850 3525);
FORCEPROP 2 LAST VALUE DELTA-L 4.0
R 2
J 0
(-4850 3425);
DISPLAY 0.680851 (-4850 3425);
FORCEPROP 2 LAST PART_TYPE SMLF
R 2
J 0
(-4850 3375);
DISPLAY 0.680851 (-4850 3375);
FORCEPROP 1 LAST CDS_LMAN_SYM_OUTLINE -150,100,150,-100
R 2
J 0
(-5000 3675);
DISPLAY 0.468085 (-5000 3675);
PAINT GREEN (-5000 3675);
DISPLAY INVISIBLE (-5000 3675);
FORCEPROP 2 LAST CDS_LIB pure_quanta
R 2
J 0
(-5000 3675);
DISPLAY INVISIBLE (-5000 3675);
FORCEPROP 1 LAST PATH I64
R 2
J 0
(-5000 3675);
DISPLAY 0.723404 (-5000 3675);
PAINT GREEN (-5000 3675);
DISPLAY INVISIBLE (-5000 3675);
FORCEPROP 1 LAST NEEDS_NO_SIZE TRUE
R 2
J 0
(-5000 3675);
DISPLAY 0.723404 (-5000 3675);
PAINT GREEN (-5000 3675);
DISPLAY INVISIBLE (-5000 3675);
FORCEPROP 1 LAST LOCATION J12
R 2
J 0
(-4846 3296);
DISPLAY 0.723404 (-4846 3296);
PAINT GREEN (-4846 3296);
FORCEPROP 0 LASTPIN (-5300 3675) $PN 1
J 2
(-5310 3685);
DISPLAY 0.680851 (-5310 3685);
PAINT MONO (-5310 3685);
FORCEPROP 0 LASTPIN (-5300 3625) $PN 2
J 2
(-5310 3635);
DISPLAY 0.680851 (-5310 3635);
PAINT MONO (-5310 3635);
FORCEPROP 0 LASTPIN (-4700 3625) $PN 3
J 0
(-4690 3635);
DISPLAY 0.680851 (-4690 3635);
PAINT MONO (-4690 3635);
FORCEPROP 0 LAST $SEC 1
J 0
(-4700 3800);
DISPLAY 0.680851 (-4700 3800);
PAINT MONO (-4700 3800);
DISPLAY INVISIBLE (-4700 3800);
FORCEPROP 0 LAST CDS_SEC 1
J 0
(-4700 3800);
DISPLAY 0.680851 (-4700 3800);
DISPLAY INVISIBLE (-4700 3800);
FORCEADD PICOPROBE_BXA..1
R 4
(-5000 2800);
FORCEPROP 1 LAST MATERIAL EMPTY
R 2
J 0
(-4846 2695);
DISPLAY 0.723404 (-4846 2695);
PAINT GREEN (-4846 2695);
FORCEPROP 1 LAST PART_NUMBER TP33
R 2
J 0
(-4850 2650);
DISPLAY 0.723404 (-4850 2650);
PAINT GREEN (-4850 2650);
FORCEPROP 2 LAST VALUE DELTA-L 4.0
R 2
J 0
(-4850 2550);
DISPLAY 0.680851 (-4850 2550);
FORCEPROP 2 LAST PART_TYPE SMLF
R 2
J 0
(-4850 2500);
DISPLAY 0.680851 (-4850 2500);
FORCEPROP 1 LAST NEEDS_NO_SIZE TRUE
R 2
J 0
(-5000 2800);
DISPLAY 0.723404 (-5000 2800);
PAINT GREEN (-5000 2800);
DISPLAY INVISIBLE (-5000 2800);
FORCEPROP 1 LAST CDS_LMAN_SYM_OUTLINE -150,100,150,-100
R 2
J 0
(-5000 2800);
DISPLAY 0.468085 (-5000 2800);
PAINT GREEN (-5000 2800);
DISPLAY INVISIBLE (-5000 2800);
FORCEPROP 1 LAST PATH I65
R 2
J 0
(-5000 2800);
DISPLAY 0.723404 (-5000 2800);
PAINT GREEN (-5000 2800);
DISPLAY INVISIBLE (-5000 2800);
FORCEPROP 2 LAST CDS_LIB pure_quanta
J 0
(-5000 2800);
DISPLAY INVISIBLE (-5000 2800);
FORCEPROP 1 LAST LOCATION J29
R 2
J 0
(-4846 2421);
DISPLAY 0.723404 (-4846 2421);
PAINT GREEN (-4846 2421);
FORCEPROP 0 LASTPIN (-5300 2800) $PN 1
J 2
(-5310 2810);
DISPLAY 0.680851 (-5310 2810);
PAINT MONO (-5310 2810);
FORCEPROP 0 LASTPIN (-5300 2750) $PN 2
J 2
(-5310 2760);
DISPLAY 0.680851 (-5310 2760);
PAINT MONO (-5310 2760);
FORCEPROP 0 LASTPIN (-4700 2750) $PN 3
J 0
(-4690 2760);
DISPLAY 0.680851 (-4690 2760);
PAINT MONO (-4690 2760);
FORCEPROP 0 LAST $SEC 1
J 0
(-4700 2925);
DISPLAY 0.680851 (-4700 2925);
PAINT MONO (-4700 2925);
DISPLAY INVISIBLE (-4700 2925);
FORCEPROP 0 LAST CDS_SEC 1
J 0
(-4700 2925);
DISPLAY 0.680851 (-4700 2925);
DISPLAY INVISIBLE (-4700 2925);
FORCEADD PICOPROBE_BXA..1
R 4
(-4925 600);
FORCEPROP 2 LAST PART_TYPE SMLF
R 2
J 0
(-4775 300);
DISPLAY 0.680851 (-4775 300);
FORCEPROP 2 LAST VALUE DELTA-L 4.0
R 2
J 0
(-4775 350);
DISPLAY 0.680851 (-4775 350);
FORCEPROP 1 LAST PART_NUMBER TP33
R 2
J 0
(-4775 450);
DISPLAY 0.723404 (-4775 450);
PAINT GREEN (-4775 450);
FORCEPROP 1 LAST MATERIAL EMPTY
R 2
J 0
(-4771 495);
DISPLAY 0.723404 (-4771 495);
PAINT GREEN (-4771 495);
FORCEPROP 1 LAST NEEDS_NO_SIZE TRUE
R 2
J 0
(-4925 600);
DISPLAY 0.723404 (-4925 600);
PAINT GREEN (-4925 600);
DISPLAY INVISIBLE (-4925 600);
FORCEPROP 1 LAST CDS_LMAN_SYM_OUTLINE -150,100,150,-100
R 2
J 0
(-4925 600);
DISPLAY 0.468085 (-4925 600);
PAINT GREEN (-4925 600);
DISPLAY INVISIBLE (-4925 600);
FORCEPROP 1 LAST PATH I66
R 2
J 0
(-4925 600);
DISPLAY 0.723404 (-4925 600);
PAINT GREEN (-4925 600);
DISPLAY INVISIBLE (-4925 600);
FORCEPROP 2 LAST CDS_LIB pure_quanta
J 0
(-4925 600);
DISPLAY INVISIBLE (-4925 600);
FORCEPROP 1 LAST LOCATION J22
R 2
J 0
(-4771 221);
DISPLAY 0.723404 (-4771 221);
PAINT GREEN (-4771 221);
FORCEPROP 0 LASTPIN (-5225 600) $PN 1
J 2
(-5235 610);
DISPLAY 0.680851 (-5235 610);
PAINT MONO (-5235 610);
FORCEPROP 0 LASTPIN (-5225 550) $PN 2
J 2
(-5235 560);
DISPLAY 0.680851 (-5235 560);
PAINT MONO (-5235 560);
FORCEPROP 0 LASTPIN (-4625 550) $PN 3
J 0
(-4615 560);
DISPLAY 0.680851 (-4615 560);
PAINT MONO (-4615 560);
FORCEPROP 0 LAST $SEC 1
J 0
(-4625 725);
DISPLAY 0.680851 (-4625 725);
PAINT MONO (-4625 725);
DISPLAY INVISIBLE (-4625 725);
FORCEPROP 0 LAST CDS_SEC 1
J 0
(-4625 725);
DISPLAY 0.680851 (-4625 725);
DISPLAY INVISIBLE (-4625 725);
FORCEADD PICOPROBE_BXA..1
R 4
(-4900 -325);
FORCEPROP 1 LAST MATERIAL EMPTY
R 2
J 0
(-4746 -430);
DISPLAY 0.723404 (-4746 -430);
PAINT GREEN (-4746 -430);
FORCEPROP 1 LAST PART_NUMBER TP33
R 2
J 0
(-4750 -475);
DISPLAY 0.723404 (-4750 -475);
PAINT GREEN (-4750 -475);
FORCEPROP 2 LAST VALUE DELTA-L 4.0
R 2
J 0
(-4750 -575);
DISPLAY 0.680851 (-4750 -575);
FORCEPROP 2 LAST PART_TYPE SMLF
R 2
J 0
(-4750 -625);
DISPLAY 0.680851 (-4750 -625);
FORCEPROP 2 LAST CDS_LIB pure_quanta
J 0
(-4900 -325);
DISPLAY INVISIBLE (-4900 -325);
FORCEPROP 1 LAST PATH I67
R 2
J 0
(-4900 -325);
DISPLAY 0.723404 (-4900 -325);
PAINT GREEN (-4900 -325);
DISPLAY INVISIBLE (-4900 -325);
FORCEPROP 1 LAST CDS_LMAN_SYM_OUTLINE -150,100,150,-100
R 2
J 0
(-4900 -325);
DISPLAY 0.468085 (-4900 -325);
PAINT GREEN (-4900 -325);
DISPLAY INVISIBLE (-4900 -325);
FORCEPROP 1 LAST NEEDS_NO_SIZE TRUE
R 2
J 0
(-4900 -325);
DISPLAY 0.723404 (-4900 -325);
PAINT GREEN (-4900 -325);
DISPLAY INVISIBLE (-4900 -325);
FORCEPROP 1 LAST LOCATION J30
R 2
J 0
(-4746 -704);
DISPLAY 0.723404 (-4746 -704);
PAINT GREEN (-4746 -704);
FORCEPROP 0 LASTPIN (-5200 -325) $PN 1
J 2
(-5210 -315);
DISPLAY 0.680851 (-5210 -315);
PAINT MONO (-5210 -315);
FORCEPROP 0 LASTPIN (-5200 -375) $PN 2
J 2
(-5210 -365);
DISPLAY 0.680851 (-5210 -365);
PAINT MONO (-5210 -365);
FORCEPROP 0 LASTPIN (-4600 -375) $PN 3
J 0
(-4590 -365);
DISPLAY 0.680851 (-4590 -365);
PAINT MONO (-4590 -365);
FORCEPROP 0 LAST $SEC 1
J 0
(-4600 -200);
DISPLAY 0.680851 (-4600 -200);
PAINT MONO (-4600 -200);
DISPLAY INVISIBLE (-4600 -200);
FORCEPROP 0 LAST CDS_SEC 1
J 0
(-4600 -200);
DISPLAY 0.680851 (-4600 -200);
DISPLAY INVISIBLE (-4600 -200);
FORCEADD PICOPROBE_BXA..1
R 4
(-625 -375);
FORCEPROP 2 LAST PART_TYPE SMLF
R 2
J 0
(-475 -675);
DISPLAY 0.680851 (-475 -675);
FORCEPROP 2 LAST VALUE DELTA-L 4.0
R 2
J 0
(-475 -625);
DISPLAY 0.680851 (-475 -625);
FORCEPROP 1 LAST PART_NUMBER TP33
R 2
J 0
(-475 -525);
DISPLAY 0.723404 (-475 -525);
PAINT GREEN (-475 -525);
FORCEPROP 1 LAST MATERIAL EMPTY
R 2
J 0
(-471 -480);
DISPLAY 0.723404 (-471 -480);
PAINT GREEN (-471 -480);
FORCEPROP 1 LAST NEEDS_NO_SIZE TRUE
R 2
J 0
(-625 -375);
DISPLAY 0.723404 (-625 -375);
PAINT GREEN (-625 -375);
DISPLAY INVISIBLE (-625 -375);
FORCEPROP 1 LAST CDS_LMAN_SYM_OUTLINE -150,100,150,-100
R 2
J 0
(-625 -375);
DISPLAY 0.468085 (-625 -375);
PAINT GREEN (-625 -375);
DISPLAY INVISIBLE (-625 -375);
FORCEPROP 1 LAST PATH I68
R 2
J 0
(-625 -375);
DISPLAY 0.723404 (-625 -375);
PAINT GREEN (-625 -375);
DISPLAY INVISIBLE (-625 -375);
FORCEPROP 2 LAST CDS_LIB pure_quanta
J 0
(-625 -375);
DISPLAY INVISIBLE (-625 -375);
FORCEPROP 1 LAST LOCATION J24
R 2
J 0
(-471 -754);
DISPLAY 0.723404 (-471 -754);
PAINT GREEN (-471 -754);
FORCEPROP 0 LASTPIN (-925 -375) $PN 1
J 2
(-935 -365);
DISPLAY 0.680851 (-935 -365);
PAINT MONO (-935 -365);
FORCEPROP 0 LASTPIN (-925 -425) $PN 2
J 2
(-935 -415);
DISPLAY 0.680851 (-935 -415);
PAINT MONO (-935 -415);
FORCEPROP 0 LASTPIN (-325 -425) $PN 3
J 0
(-315 -415);
DISPLAY 0.680851 (-315 -415);
PAINT MONO (-315 -415);
FORCEPROP 0 LAST $SEC 1
J 0
(-325 -250);
DISPLAY 0.680851 (-325 -250);
PAINT MONO (-325 -250);
DISPLAY INVISIBLE (-325 -250);
FORCEPROP 0 LAST CDS_SEC 1
J 0
(-325 -250);
DISPLAY 0.680851 (-325 -250);
DISPLAY INVISIBLE (-325 -250);
FORCEADD PICOPROBE_BXA..1
R 4
(-625 550);
FORCEPROP 1 LAST MATERIAL EMPTY
R 2
J 0
(-471 445);
DISPLAY 0.723404 (-471 445);
PAINT GREEN (-471 445);
FORCEPROP 1 LAST PART_NUMBER TP33
R 2
J 0
(-475 400);
DISPLAY 0.723404 (-475 400);
PAINT GREEN (-475 400);
FORCEPROP 2 LAST VALUE DELTA-L 4.0
R 2
J 0
(-475 300);
DISPLAY 0.680851 (-475 300);
FORCEPROP 2 LAST PART_TYPE SMLF
R 2
J 0
(-475 250);
DISPLAY 0.680851 (-475 250);
FORCEPROP 1 LAST NEEDS_NO_SIZE TRUE
R 2
J 0
(-625 550);
DISPLAY 0.723404 (-625 550);
PAINT GREEN (-625 550);
DISPLAY INVISIBLE (-625 550);
FORCEPROP 1 LAST CDS_LMAN_SYM_OUTLINE -150,100,150,-100
R 2
J 0
(-625 550);
DISPLAY 0.468085 (-625 550);
PAINT GREEN (-625 550);
DISPLAY INVISIBLE (-625 550);
FORCEPROP 1 LAST PATH I69
R 2
J 0
(-625 550);
DISPLAY 0.723404 (-625 550);
PAINT GREEN (-625 550);
DISPLAY INVISIBLE (-625 550);
FORCEPROP 2 LAST CDS_LIB pure_quanta
J 0
(-625 550);
DISPLAY INVISIBLE (-625 550);
FORCEPROP 1 LAST LOCATION J23
R 2
J 0
(-471 171);
DISPLAY 0.723404 (-471 171);
PAINT GREEN (-471 171);
FORCEPROP 0 LASTPIN (-925 550) $PN 1
J 2
(-935 560);
DISPLAY 0.680851 (-935 560);
PAINT MONO (-935 560);
FORCEPROP 0 LASTPIN (-925 500) $PN 2
J 2
(-935 510);
DISPLAY 0.680851 (-935 510);
PAINT MONO (-935 510);
FORCEPROP 0 LASTPIN (-325 500) $PN 3
J 0
(-315 510);
DISPLAY 0.680851 (-315 510);
PAINT MONO (-315 510);
FORCEPROP 0 LAST $SEC 1
J 0
(-325 675);
DISPLAY 0.680851 (-325 675);
PAINT MONO (-325 675);
DISPLAY INVISIBLE (-325 675);
FORCEPROP 0 LAST CDS_SEC 1
J 0
(-325 675);
DISPLAY 0.680851 (-325 675);
DISPLAY INVISIBLE (-325 675);
FORCEADD PICOPROBE_BXA..1
R 4
(-825 2700);
FORCEPROP 1 LAST MATERIAL EMPTY
R 2
J 0
(-671 2595);
DISPLAY 0.723404 (-671 2595);
PAINT GREEN (-671 2595);
FORCEPROP 1 LAST PART_NUMBER TP33
R 2
J 0
(-675 2550);
DISPLAY 0.723404 (-675 2550);
PAINT GREEN (-675 2550);
FORCEPROP 2 LAST VALUE DELTA-L 4.0
R 2
J 0
(-675 2450);
DISPLAY 0.680851 (-675 2450);
FORCEPROP 2 LAST PART_TYPE SMLF
R 2
J 0
(-675 2400);
DISPLAY 0.680851 (-675 2400);
FORCEPROP 1 LAST NEEDS_NO_SIZE TRUE
R 2
J 0
(-825 2700);
DISPLAY 0.723404 (-825 2700);
PAINT GREEN (-825 2700);
DISPLAY INVISIBLE (-825 2700);
FORCEPROP 1 LAST CDS_LMAN_SYM_OUTLINE -150,100,150,-100
R 2
J 0
(-825 2700);
DISPLAY 0.468085 (-825 2700);
PAINT GREEN (-825 2700);
DISPLAY INVISIBLE (-825 2700);
FORCEPROP 1 LAST PATH I70
R 2
J 0
(-825 2700);
DISPLAY 0.723404 (-825 2700);
PAINT GREEN (-825 2700);
DISPLAY INVISIBLE (-825 2700);
FORCEPROP 2 LAST CDS_LIB pure_quanta
J 0
(-825 2700);
DISPLAY INVISIBLE (-825 2700);
FORCEPROP 1 LAST LOCATION J20
R 2
J 0
(-671 2321);
DISPLAY 0.723404 (-671 2321);
PAINT GREEN (-671 2321);
FORCEPROP 0 LASTPIN (-1125 2700) $PN 1
J 2
(-1135 2710);
DISPLAY 0.680851 (-1135 2710);
PAINT MONO (-1135 2710);
FORCEPROP 0 LASTPIN (-1125 2650) $PN 2
J 2
(-1135 2660);
DISPLAY 0.680851 (-1135 2660);
PAINT MONO (-1135 2660);
FORCEPROP 0 LASTPIN (-525 2650) $PN 3
J 0
(-515 2660);
DISPLAY 0.680851 (-515 2660);
PAINT MONO (-515 2660);
FORCEPROP 0 LAST $SEC 1
J 0
(-525 2825);
DISPLAY 0.680851 (-525 2825);
PAINT MONO (-525 2825);
DISPLAY INVISIBLE (-525 2825);
FORCEPROP 0 LAST CDS_SEC 1
J 0
(-525 2825);
DISPLAY 0.680851 (-525 2825);
DISPLAY INVISIBLE (-525 2825);
FORCEADD PICOPROBE_BXA..1
R 4
(-825 3625);
FORCEPROP 1 LAST PART_NUMBER TP33
R 2
J 0
(-675 3475);
DISPLAY 0.723404 (-675 3475);
PAINT GREEN (-675 3475);
FORCEPROP 2 LAST VALUE DELTA-L 4.0
R 2
J 0
(-675 3375);
DISPLAY 0.680851 (-675 3375);
FORCEPROP 2 LAST PART_TYPE SMLF
R 2
J 0
(-675 3325);
DISPLAY 0.680851 (-675 3325);
FORCEPROP 1 LAST MATERIAL EMPTY
R 2
J 0
(-671 3520);
DISPLAY 0.723404 (-671 3520);
PAINT GREEN (-671 3520);
FORCEPROP 1 LAST NEEDS_NO_SIZE TRUE
R 2
J 0
(-825 3625);
DISPLAY 0.723404 (-825 3625);
PAINT GREEN (-825 3625);
DISPLAY INVISIBLE (-825 3625);
FORCEPROP 1 LAST CDS_LMAN_SYM_OUTLINE -150,100,150,-100
R 2
J 0
(-825 3625);
DISPLAY 0.468085 (-825 3625);
PAINT GREEN (-825 3625);
DISPLAY INVISIBLE (-825 3625);
FORCEPROP 1 LAST PATH I71
R 2
J 0
(-825 3625);
DISPLAY 0.723404 (-825 3625);
PAINT GREEN (-825 3625);
DISPLAY INVISIBLE (-825 3625);
FORCEPROP 2 LAST CDS_LIB pure_quanta
J 0
(-825 3625);
DISPLAY INVISIBLE (-825 3625);
FORCEPROP 1 LAST LOCATION J19
R 2
J 0
(-671 3246);
DISPLAY 0.723404 (-671 3246);
PAINT GREEN (-671 3246);
FORCEPROP 0 LASTPIN (-1125 3625) $PN 1
J 2
(-1135 3635);
DISPLAY 0.680851 (-1135 3635);
PAINT MONO (-1135 3635);
FORCEPROP 0 LASTPIN (-1125 3575) $PN 2
J 2
(-1135 3585);
DISPLAY 0.680851 (-1135 3585);
PAINT MONO (-1135 3585);
FORCEPROP 0 LASTPIN (-525 3575) $PN 3
J 0
(-515 3585);
DISPLAY 0.680851 (-515 3585);
PAINT MONO (-515 3585);
FORCEPROP 0 LAST $SEC 1
J 0
(-525 3750);
DISPLAY 0.680851 (-525 3750);
PAINT MONO (-525 3750);
DISPLAY INVISIBLE (-525 3750);
FORCEPROP 0 LAST CDS_SEC 1
J 0
(-525 3750);
DISPLAY 0.680851 (-525 3750);
DISPLAY INVISIBLE (-525 3750);
FORCEADD QUANTA_TITLE_BLOCK_C..1
(600 -2225);
FORCEPROP 0 LAST CDS_CON_LAST_MODIFIED Fri Aug 25 17:25:50 2023
J 0
(-1285 -2210);
DISPLAY INVISIBLE (-1285 -2210);
FORCEPROP 2 LAST Q_DEPT 
J 1
(-3163 -2176);
DISPLAY 1.957447 (-3163 -2176);
PAINT GREEN (-3163 -2176);
FORCEPROP 1 LAST CUSTOM_TXT_CDS <CON_LAST_MODIFIED>
J 0
(-1285 -2210);
DISPLAY 0.978723 (-1285 -2210);
FORCEPROP 2 LAST CUSTOM_TXT_CDS <XR_PAGE_TITLE>
J 0
(-7290 3025);
DISPLAY 0.638298 (-7290 3025);
PAINT PINK (-7290 3025);
DISPLAY INVISIBLE (-7290 3025);
FORCEPROP 1 LAST CUSTOM_TXT_CDS <NAME_2>
J 0
(-2575 -2175);
FORCEPROP 1 LAST CUSTOM_TXT_CDS <NAME_1>
J 0
(-2575 -2050);
FORCEPROP 1 LAST CUSTOM_TXT_CDS <Q_NUMBER>
J 0
(-803 -2122);
DISPLAY 1.212766 (-803 -2122);
FORCEPROP 1 LAST CUSTOM_TXT_CDS <Q_PROJ>
J 0
(-1782 -2123);
DISPLAY 1.212766 (-1782 -2123);
FORCEPROP 1 LAST CUSTOM_TXT_CDS <Q_REV>
J 0
(416 -2122);
DISPLAY 1.212766 (416 -2122);
FORCEPROP 1 LAST CUSTOM_TXT_CDS <CON_PAGE_NUM> OF <CON_TOTAL_PAGES>
J 0
(154 -2207);
DISPLAY 0.978723 (154 -2207);
FORCEPROP 1 LAST Q_TITLE DELTA - L
J 0
(-8766 -2199);
DISPLAY 2.446809 (-8766 -2199);
PAINT GREEN (-8766 -2199);
FORCEPROP 1 LAST COMMENT_BODY TRUE
J 0
(612 -2238);
DISPLAY 0.978723 (612 -2238);
PAINT PEACH (612 -2238);
DISPLAY INVISIBLE (612 -2238);
FORCEPROP 2 LAST CDS_LIB pure_quanta
J 0
(600 -2225);
DISPLAY INVISIBLE (600 -2225);
FORCEPROP 1 LAST CDS_LMAN_SYM_OUTLINE -9475,6775,100,-125
J 0
(600 -2225);
DISPLAY 0.468085 (600 -2225);
PAINT GREEN (600 -2225);
DISPLAY INVISIBLE (600 -2225);
FORCEPROP 2 LAST PAGE_BORDER TRUE
J 0
(-7290 3025);
DISPLAY 0.638298 (-7290 3025);
PAINT PINK (-7290 3025);
DISPLAY INVISIBLE (-7290 3025);
FORCEPROP 2 LAST CDS_XR_PAGE_TITLE CR-58 : @SCM_LIB.SCM(SCH_1):PAGE58
J 0
(-7290 3025);
DISPLAY 0.638298 (-7290 3025);
PAINT PINK (-7290 3025);
DISPLAY INVISIBLE (-7290 3025);
WIRE 16 -1 (-225 200)(-225 500);
WIRE 16 -1 (-4600 3325)(-4600 3625);
WIRE 16 -1 (-3700 -750)(-3700 -375);
WIRE 16 -1 (-3700 200)(-3700 550);
WIRE 16 -1 (-8000 250)(-8000 600);
WIRE 16 -1 (-4600 2450)(-4600 2750);
WIRE 16 -1 (-3900 3275)(-3900 3625);
WIRE 16 -1 (-8075 2450)(-8075 2800);
WIRE 16 -1 (-8075 3325)(-8075 3675);
WIRE 16 -1 (-7975 -675)(-7975 -325);
WIRE 16 -1 (-4500 -675)(-4500 -375);
WIRE 16 -1 (-4525 250)(-4525 550);
WIRE 16 -1 (-425 2325)(-425 2650);
WIRE 16 -1 (-225 -750)(-225 -425);
WIRE 16 -1 (-3900 2325)(-3900 2700);
WIRE 16 -1 (-425 3275)(-425 3575);
WIRE 16 -1 (-525 2650)(-425 2650);
WIRE 16 -1 (-8075 3675)(-7975 3675);
WIRE 16 -1 (-3900 2700)(-3800 2700);
WIRE 16 -1 (-325 -425)(-225 -425);
WIRE 16 -1 (-3700 -375)(-3600 -375);
WIRE 16 -1 (-4625 550)(-4525 550);
WIRE 16 -1 (-8000 600)(-7900 600);
WIRE 16 -1 (-7975 -325)(-7875 -325);
WIRE 16 -1 (-4600 -375)(-4500 -375);
WIRE 16 -1 (-3700 550)(-3600 550);
WIRE 16 -1 (-4700 3625)(-4600 3625);
WIRE 16 -1 (-325 500)(-225 500);
WIRE 16 -1 (-3900 3625)(-3800 3625);
WIRE 16 -1 (-525 3575)(-425 3575);
WIRE 16 -1 (-4700 2750)(-4600 2750);
WIRE 16 -1 (-8075 2800)(-7975 2800);
WIRE 16 -1 (-5300 2800)(-7375 2800);
FORCEPROP 2 LAST SIG_NAME 85_5INCH_IN1_DP
J 1
(-6325 2810);
DISPLAY 0.808511 (-6325 2810);
WIRE 16 -1 (-1125 3575)(-3200 3575);
FORCEPROP 2 LAST SIG_NAME 85_5INCH_IN4_DN
J 1
(-2150 3585);
DISPLAY 0.808511 (-2150 3585);
WIRE 16 -1 (-1125 3625)(-3200 3625);
FORCEPROP 2 LAST SIG_NAME 85_5INCH_IN4_DP
J 1
(-2150 3635);
DISPLAY 0.808511 (-2150 3635);
WIRE 16 -1 (-1125 2700)(-3200 2700);
FORCEPROP 2 LAST SIG_NAME 85_5INCH_BOT_DP
J 1
(-2150 2710);
DISPLAY 0.808511 (-2150 2710);
WIRE 16 -1 (-1125 2650)(-3200 2650);
FORCEPROP 2 LAST SIG_NAME 85_5INCH_BOT_DN
J 1
(-2150 2660);
DISPLAY 0.808511 (-2150 2660);
WIRE 16 -1 (-925 -375)(-3000 -375);
FORCEPROP 2 LAST SIG_NAME 85_10INCH_BOT_DP
J 1
(-1950 -365);
DISPLAY 0.808511 (-1950 -365);
WIRE 16 -1 (-925 -425)(-3000 -425);
FORCEPROP 2 LAST SIG_NAME 85_10INCH_BOT_DN
J 1
(-1950 -415);
DISPLAY 0.808511 (-1950 -415);
WIRE 16 -1 (-925 500)(-3000 500);
FORCEPROP 2 LAST SIG_NAME 85_10INCH_IN4_DN
J 1
(-1950 510);
DISPLAY 0.808511 (-1950 510);
WIRE 16 -1 (-925 550)(-3000 550);
FORCEPROP 2 LAST SIG_NAME 85_10INCH_IN4_DP
J 1
(-1950 560);
DISPLAY 0.808511 (-1950 560);
WIRE 16 -1 (-5200 -325)(-7275 -325);
FORCEPROP 2 LAST SIG_NAME 85_10INCH_IN1_DP
J 1
(-6225 -315);
DISPLAY 0.808511 (-6225 -315);
WIRE 16 -1 (-5200 -375)(-7275 -375);
FORCEPROP 2 LAST SIG_NAME 85_10INCH_IN1_DN
J 1
(-6225 -365);
DISPLAY 0.808511 (-6225 -365);
WIRE 16 -1 (-5225 550)(-7300 550);
FORCEPROP 2 LAST SIG_NAME 85_10INCH_TOP_DN
J 1
(-6250 560);
DISPLAY 0.808511 (-6250 560);
WIRE 16 -1 (-5225 600)(-7300 600);
FORCEPROP 2 LAST SIG_NAME 85_10INCH_TOP_DP
J 1
(-6250 610);
DISPLAY 0.808511 (-6250 610);
WIRE 16 -1 (-5300 2750)(-7375 2750);
FORCEPROP 2 LAST SIG_NAME 85_5INCH_IN1_DN
J 1
(-6325 2760);
DISPLAY 0.808511 (-6325 2760);
WIRE 16 -1 (-5300 3675)(-7375 3675);
FORCEPROP 2 LAST SIG_NAME 85_5INCH_TOP_DP
J 1
(-6325 3685);
DISPLAY 0.808511 (-6325 3685);
WIRE 16 -1 (-5300 3625)(-7375 3625);
FORCEPROP 2 LAST SIG_NAME 85_5INCH_TOP_DN
J 1
(-6325 3635);
DISPLAY 0.808511 (-6325 3635);
FORCENOTE
10 INCH DELTA L
(-8400 1100) 0;
DISPLAY LEFT (-8400 1100);
DISPLAY 3.148936 (-8400 1100);
PAINT WHITE (-8400 1100);
FORCENOTE
5 INCH DELTA L
(-8500 4075) 0;
DISPLAY LEFT (-8500 4075);
DISPLAY 3.148936 (-8500 4075);
PAINT WHITE (-8500 4075);
QUIT
